(kicad_pcb
	(version 20260206)
	(generator "pcbnew")
	(generator_version "10.0")
	(general
		(thickness 1.6)
		(legacy_teardrops no)
	)
	(paper "A4")
	(title_block
		(title "peb — Lightning_PEB_BRD.brd")
		(comment 1 "Lightning (Wiwynn / Facebook NVMe JBOF) / footprints 134-138 of 2563")
	)
	(layers
		(0 "F.Cu" signal "TOP")
		(4 "In1.Cu" signal "L2GND")
		(6 "In2.Cu" signal "L3")
		(8 "In3.Cu" signal "L4VCC")
		(10 "In4.Cu" signal "L5VCC")
		(12 "In5.Cu" signal "L6")
		(14 "In6.Cu" signal "L7GND")
		(2 "B.Cu" signal "BOTTOM")
		(9 "F.Adhes" user "F.Adhesive")
		(11 "B.Adhes" user "B.Adhesive")
		(13 "F.Paste" user "Package Geometry/Pastemask Top")
		(15 "B.Paste" user "Package Geometry/Pastemask Bottom")
		(5 "F.SilkS" user "Ref Des/Silkscreen Top")
		(7 "B.SilkS" user "Ref Des/Silkscreen Bottom")
		(1 "F.Mask" user "Board Geometry/Soldermask Top")
		(3 "B.Mask" user "Board Geometry/Soldermask Bottom")
		(17 "Dwgs.User" user "User.Drawings")
		(19 "Cmts.User" user "User.Comments")
		(21 "Eco1.User" user "User.Eco1")
		(23 "Eco2.User" user "User.Eco2")
		(25 "Edge.Cuts" user "Board Geometry/Outline")
		(27 "Margin" user)
		(31 "F.CrtYd" user "Package Geometry/Place Bound Top")
		(29 "B.CrtYd" user "Package Geometry/Place Bound Bottom")
		(35 "F.Fab" user "Ref Des/Assembly Top")
		(33 "B.Fab" user "Ref Des/Assembly Bottom")
	)
	(footprint ""
		(layer "F.Cu")
		(at 13.9446 -195.7832 -90)
		(property "Reference" "R9027"
			(at 0 0 270)
			(layer "F.SilkS")
			(hide yes)
			(effects
				(font
					(size 1.27 1.27)
				)
			)
		)
		(property "Value" "63K4R2F-2-GP"
			(at 0.064008 -3.993896 270)
			(unlocked yes)
			(layer "F.Fab")
			(hide yes)
			(effects
				(font
					(size 1.016 1.016)
					(thickness 0.1524)
				)
			)
		)
		(property "Device Type" "R402H16"
			(at 0.064008 -5.517896 270)
			(unlocked yes)
			(layer "F.Fab")
			(hide yes)
			(effects
				(font
					(size 1.016 1.016)
					(thickness 0.1524)
				)
			)
		)
		(duplicate_pad_numbers_are_jumpers no)
		(fp_line
			(start -0.508 -0.9398)
			(end -0.508 0.9398)
			(stroke
				(width 0.1524)
				(type default)
			)
			(layer "F.SilkS")
		)
		(fp_line
			(start 0.508 -0.9398)
			(end -0.508 -0.9398)
			(stroke
				(width 0.1524)
				(type default)
			)
			(layer "F.SilkS")
		)
		(fp_rect
			(start -0.508 0.9398)
			(end 0.508 -0.9398)
			(stroke
				(width 0)
				(type default)
			)
			(fill no)
			(layer "F.CrtYd")
		)
		(fp_rect
			(start -0.508 0.9398)
			(end 0.508 -0.9398)
			(stroke
				(width 0)
				(type default)
			)
			(fill no)
			(layer "F.Fab")
		)
		(pad "1" smd custom
			(at 0 -0.4445 270)
			(size 0.1397 0.1397)
			(layers "F.Cu" "F.Mask" "F.Paste")
			(net "MB0_ISET_R")
			(options
				(clearance outline)
				(anchor circle)
			)
			(primitives
				(gr_poly
					(pts
						(arc
							(start -0.1778 -0.2794)
							(mid -0.249642 -0.249642)
							(end -0.2794 -0.1778)
						)
						(arc
							(start -0.2794 0.1778)
							(mid -0.249642 0.249642)
							(end -0.1778 0.2794)
						)
						(arc
							(start 0.1778 0.2794)
							(mid 0.249642 0.249642)
							(end 0.2794 0.1778)
						)
						(arc
							(start 0.2794 -0.1778)
							(mid 0.249642 -0.249642)
							(end 0.1778 -0.2794)
						)
					)
					(width 0)
					(fill yes)
				)
			)
		)
		(pad "2" smd custom
			(at 0 0.4445 270)
			(size 0.1397 0.1397)
			(layers "F.Cu" "F.Mask" "F.Paste")
			(net "AGND_CURRENT_MON")
			(options
				(clearance outline)
				(anchor circle)
			)
			(primitives
				(gr_poly
					(pts
						(arc
							(start -0.1778 -0.2794)
							(mid -0.249642 -0.249642)
							(end -0.2794 -0.1778)
						)
						(arc
							(start -0.2794 0.1778)
							(mid -0.249642 0.249642)
							(end -0.1778 0.2794)
						)
						(arc
							(start 0.1778 0.2794)
							(mid 0.249642 0.249642)
							(end 0.2794 0.1778)
						)
						(arc
							(start 0.2794 -0.1778)
							(mid 0.249642 -0.249642)
							(end 0.1778 -0.2794)
						)
					)
					(width 0)
					(fill yes)
				)
			)
		)
	)
	(footprint ""
		(layer "F.Cu")
		(at 241.1476 -11.2014 -90)
		(property "Reference" "L1"
			(at 0 0 270)
			(layer "F.SilkS")
			(hide yes)
			(effects
				(font
					(size 1.27 1.27)
				)
			)
		)
		(property "Value" "IND-10UH-147-GP-U"
			(at -4.699 -4.0132 270)
			(unlocked yes)
			(layer "F.Fab")
			(hide yes)
			(effects
				(font
					(size 1.016 1.016)
					(thickness 0.1524)
				)
			)
		)
		(property "Device Type" "L7066-1830-UH119"
			(at -4.699 -5.5372 270)
			(unlocked yes)
			(layer "F.Fab")
			(hide yes)
			(effects
				(font
					(size 1.016 1.016)
					(thickness 0.1524)
				)
			)
		)
		(duplicate_pad_numbers_are_jumpers no)
		(fp_line
			(start -3.556 4.4958)
			(end -3.556 -4.4958)
			(stroke
				(width 0.1524)
				(type default)
			)
			(layer "F.SilkS")
		)
		(fp_line
			(start 3.556 4.4958)
			(end -3.556 4.4958)
			(stroke
				(width 0.1524)
				(type default)
			)
			(layer "F.SilkS")
		)
		(fp_line
			(start -3.556 -4.4958)
			(end 3.556 -4.4958)
			(stroke
				(width 0.1524)
				(type default)
			)
			(layer "F.SilkS")
		)
		(fp_line
			(start 3.556 -4.4958)
			(end 3.556 4.4958)
			(stroke
				(width 0.1524)
				(type default)
			)
			(layer "F.SilkS")
		)
		(fp_rect
			(start -3.302 3.4798)
			(end 3.302 -3.4798)
			(stroke
				(width 0)
				(type default)
			)
			(fill no)
			(layer "F.CrtYd")
		)
		(fp_poly
			(pts
				(xy -3.81 4.572) (xy -3.81 -4.572) (xy 3.81 -4.572) (xy 3.81 -0.5588) (xy 3.302 -0.5588) (xy 3.302 -3.4798)
				(xy -3.302 -3.4798) (xy -3.302 3.4798) (xy 3.302 3.4798) (xy 3.302 -0.5461) (xy 3.81 -0.5461) (xy 3.81 4.572)
			)
			(stroke
				(width 0)
				(type default)
			)
			(fill no)
			(layer "F.CrtYd")
		)
		(fp_rect
			(start -3.81 4.572)
			(end 3.81 -4.572)
			(stroke
				(width 0)
				(type default)
			)
			(fill no)
			(layer "F.Fab")
		)
		(pad "1" smd rect
			(at 0 -2.779522 270)
			(size 3.5052 2.921)
			(layers "F.Cu" "F.Mask" "F.Paste")
			(net "DUT_VDDO")
		)
		(pad "2" smd rect
			(at 0 2.779522 270)
			(size 3.5052 2.921)
			(layers "F.Cu" "F.Mask" "F.Paste")
			(net "DUT_VDDO_REF")
		)
	)
	(footprint ""
		(layer "F.Cu")
		(at 20.5613 -178.7271 180)
		(property "Reference" "R691"
			(at 0 0 180)
			(layer "F.SilkS")
			(hide yes)
			(effects
				(font
					(size 1.27 1.27)
				)
			)
		)
		(property "Value" "0R2J-2-GP"
			(at 0.064008 -3.993896 180)
			(unlocked yes)
			(layer "F.Fab")
			(hide yes)
			(effects
				(font
					(size 1.016 1.016)
					(thickness 0.1524)
				)
			)
		)
		(property "Device Type" "R402H16"
			(at 0.064008 -5.517896 180)
			(unlocked yes)
			(layer "F.Fab")
			(hide yes)
			(effects
				(font
					(size 1.016 1.016)
					(thickness 0.1524)
				)
			)
		)
		(duplicate_pad_numbers_are_jumpers no)
		(fp_line
			(start 0.508 -0.9398)
			(end -0.508 -0.9398)
			(stroke
				(width 0.1524)
				(type default)
			)
			(layer "F.SilkS")
		)
		(fp_line
			(start -0.508 -0.9398)
			(end -0.508 0.9398)
			(stroke
				(width 0.1524)
				(type default)
			)
			(layer "F.SilkS")
		)
		(fp_rect
			(start -0.508 0.9398)
			(end 0.508 -0.9398)
			(stroke
				(width 0)
				(type default)
			)
			(fill no)
			(layer "F.CrtYd")
		)
		(fp_rect
			(start -0.508 0.9398)
			(end 0.508 -0.9398)
			(stroke
				(width 0)
				(type default)
			)
			(fill no)
			(layer "F.Fab")
		)
		(pad "1" smd custom
			(at 0 -0.4445 180)
			(size 0.1397 0.1397)
			(layers "F.Cu" "F.Mask" "F.Paste")
			(net "MATED_P12V_EN")
			(options
				(clearance outline)
				(anchor circle)
			)
			(primitives
				(gr_poly
					(pts
						(arc
							(start -0.1778 -0.2794)
							(mid -0.249642 -0.249642)
							(end -0.2794 -0.1778)
						)
						(arc
							(start -0.2794 0.1778)
							(mid -0.249642 0.249642)
							(end -0.1778 0.2794)
						)
						(arc
							(start 0.1778 0.2794)
							(mid 0.249642 0.249642)
							(end 0.2794 0.1778)
						)
						(arc
							(start 0.2794 -0.1778)
							(mid 0.249642 -0.249642)
							(end 0.1778 -0.2794)
						)
					)
					(width 0)
					(fill yes)
				)
			)
		)
		(pad "2" smd custom
			(at 0 0.4445 180)
			(size 0.1397 0.1397)
			(layers "F.Cu" "F.Mask" "F.Paste")
			(net "MB0_HS_ENABLE")
			(options
				(clearance outline)
				(anchor circle)
			)
			(primitives
				(gr_poly
					(pts
						(arc
							(start -0.1778 -0.2794)
							(mid -0.249642 -0.249642)
							(end -0.2794 -0.1778)
						)
						(arc
							(start -0.2794 0.1778)
							(mid -0.249642 0.249642)
							(end -0.1778 0.2794)
						)
						(arc
							(start 0.1778 0.2794)
							(mid 0.249642 0.249642)
							(end 0.2794 0.1778)
						)
						(arc
							(start 0.2794 -0.1778)
							(mid 0.249642 -0.249642)
							(end 0.1778 -0.2794)
						)
					)
					(width 0)
					(fill yes)
				)
			)
		)
	)
	(footprint ""
		(layer "F.Cu")
		(at 262.608568 -2.813304 -90)
		(property "Reference" "R673"
			(at 0 0 270)
			(layer "F.SilkS")
			(hide yes)
			(effects
				(font
					(size 1.27 1.27)
				)
			)
		)
		(property "Value" "4K7R2F-GP"
			(at 0.064008 -3.993896 270)
			(unlocked yes)
			(layer "F.Fab")
			(hide yes)
			(effects
				(font
					(size 1.016 1.016)
					(thickness 0.1524)
				)
			)
		)
		(property "Device Type" "R402H16"
			(at 0.064008 -5.517896 270)
			(unlocked yes)
			(layer "F.Fab")
			(hide yes)
			(effects
				(font
					(size 1.016 1.016)
					(thickness 0.1524)
				)
			)
		)
		(duplicate_pad_numbers_are_jumpers no)
		(fp_line
			(start -0.508 -0.9398)
			(end -0.508 0.9398)
			(stroke
				(width 0.1524)
				(type default)
			)
			(layer "F.SilkS")
		)
		(fp_line
			(start 0.508 -0.9398)
			(end -0.508 -0.9398)
			(stroke
				(width 0.1524)
				(type default)
			)
			(layer "F.SilkS")
		)
		(fp_rect
			(start -0.508 0.9398)
			(end 0.508 -0.9398)
			(stroke
				(width 0)
				(type default)
			)
			(fill no)
			(layer "F.CrtYd")
		)
		(fp_rect
			(start -0.508 0.9398)
			(end 0.508 -0.9398)
			(stroke
				(width 0)
				(type default)
			)
			(fill no)
			(layer "F.Fab")
		)
		(pad "1" smd custom
			(at 0 -0.4445 270)
			(size 0.1397 0.1397)
			(layers "F.Cu" "F.Mask" "F.Paste")
			(net "FM_BMC_RESET#_BTN")
			(options
				(clearance outline)
				(anchor circle)
			)
			(primitives
				(gr_poly
					(pts
						(arc
							(start -0.1778 -0.2794)
							(mid -0.249642 -0.249642)
							(end -0.2794 -0.1778)
						)
						(arc
							(start -0.2794 0.1778)
							(mid -0.249642 0.249642)
							(end -0.1778 0.2794)
						)
						(arc
							(start 0.1778 0.2794)
							(mid 0.249642 0.249642)
							(end 0.2794 0.1778)
						)
						(arc
							(start 0.2794 -0.1778)
							(mid 0.249642 -0.249642)
							(end 0.1778 -0.2794)
						)
					)
					(width 0)
					(fill yes)
				)
			)
		)
		(pad "2" smd custom
			(at 0 0.4445 270)
			(size 0.1397 0.1397)
			(layers "F.Cu" "F.Mask" "F.Paste")
			(net "P3V3_STBY")
			(options
				(clearance outline)
				(anchor circle)
			)
			(primitives
				(gr_poly
					(pts
						(arc
							(start -0.1778 -0.2794)
							(mid -0.249642 -0.249642)
							(end -0.2794 -0.1778)
						)
						(arc
							(start -0.2794 0.1778)
							(mid -0.249642 0.249642)
							(end -0.1778 0.2794)
						)
						(arc
							(start 0.1778 0.2794)
							(mid 0.249642 0.249642)
							(end 0.2794 0.1778)
						)
						(arc
							(start 0.2794 -0.1778)
							(mid 0.249642 -0.249642)
							(end 0.1778 -0.2794)
						)
					)
					(width 0)
					(fill yes)
				)
			)
		)
	)
	(footprint ""
		(layer "F.Cu")
		(at 330.8858 -75.3618 -90)
		(property "Reference" "PQ20"
			(at 0 0 270)
			(layer "F.SilkS")
			(hide yes)
			(effects
				(font
					(size 1.27 1.27)
				)
			)
		)
		(property "Value" "AO3400-GP-U"
			(at 0.0254 -12.3444 270)
			(unlocked yes)
			(layer "F.Fab")
			(hide yes)
			(effects
				(font
					(size 1.016 1.016)
					(thickness 0.1524)
				)
			)
		)
		(property "Device Type" "SOT23DGS2D8H50"
			(at 0.0254 -14.2494 270)
			(unlocked yes)
			(layer "F.Fab")
			(hide yes)
			(effects
				(font
					(size 1.016 1.016)
					(thickness 0.1524)
				)
			)
		)
		(duplicate_pad_numbers_are_jumpers no)
		(fp_line
			(start -1.7018 0.254)
			(end -1.7018 -0.254)
			(stroke
				(width 0.1524)
				(type default)
			)
			(layer "F.SilkS")
		)
		(fp_line
			(start 1.7018 0.254)
			(end -1.7018 0.254)
			(stroke
				(width 0.1524)
				(type default)
			)
			(layer "F.SilkS")
		)
		(fp_line
			(start -1.7018 -0.254)
			(end 1.7018 -0.254)
			(stroke
				(width 0.1524)
				(type default)
			)
			(layer "F.SilkS")
		)
		(fp_line
			(start 1.7018 -0.254)
			(end 1.7018 0.254)
			(stroke
				(width 0.1524)
				(type default)
			)
			(layer "F.SilkS")
		)
		(fp_rect
			(start -1.778 1.9812)
			(end 1.778 -1.9812)
			(stroke
				(width 0)
				(type default)
			)
			(fill no)
			(layer "F.CrtYd")
		)
		(fp_poly
			(pts
				(xy -1.778 -1.9812) (xy 1.778 -1.9812) (xy 1.778 1.9812) (xy -1.778 1.9812)
			)
			(stroke
				(width 0)
				(type default)
			)
			(fill no)
			(layer "F.Fab")
		)
		(pad "D" smd custom
			(at 0 -1.1176 270)
			(size 0.254 0.254)
			(layers "F.Cu" "F.Mask" "F.Paste")
			(net "P0V9_E_VFB_AVS")
			(options
				(clearance outline)
				(anchor circle)
			)
			(primitives
				(gr_poly
					(pts
						(arc
							(start -0.508 -0.4064)
							(mid -0.448484 -0.550084)
							(end -0.3048 -0.6096)
						)
						(arc
							(start 0.3048 -0.6096)
							(mid 0.448484 -0.550084)
							(end 0.508 -0.4064)
						)
						(arc
							(start 0.508 0.4064)
							(mid 0.448484 0.550084)
							(end 0.3048 0.6096)
						)
						(arc
							(start -0.3048 0.6096)
							(mid -0.448484 0.550084)
							(end -0.508 0.4064)
						)
					)
					(width 0)
					(fill yes)
				)
			)
		)
		(pad "G" smd custom
			(at -1.016 1.1176 270)
			(size 0.254 0.254)
			(layers "F.Cu" "F.Mask" "F.Paste")
			(net "AVS_ENB2_R")
			(options
				(clearance outline)
				(anchor circle)
			)
			(primitives
				(gr_poly
					(pts
						(arc
							(start -0.508 -0.4064)
							(mid -0.448484 -0.550084)
							(end -0.3048 -0.6096)
						)
						(arc
							(start 0.3048 -0.6096)
							(mid 0.448484 -0.550084)
							(end 0.508 -0.4064)
						)
						(arc
							(start 0.508 0.4064)
							(mid 0.448484 0.550084)
							(end 0.3048 0.6096)
						)
						(arc
							(start -0.3048 0.6096)
							(mid -0.448484 0.550084)
							(end -0.508 0.4064)
						)
					)
					(width 0)
					(fill yes)
				)
			)
		)
		(pad "S" smd custom
			(at 1.016 1.1176 270)
			(size 0.254 0.254)
			(layers "F.Cu" "F.Mask" "F.Paste")
			(net "AGND_P0V9_E")
			(options
				(clearance outline)
				(anchor circle)
			)
			(primitives
				(gr_poly
					(pts
						(arc
							(start -0.508 -0.4064)
							(mid -0.448484 -0.550084)
							(end -0.3048 -0.6096)
						)
						(arc
							(start 0.3048 -0.6096)
							(mid 0.448484 -0.550084)
							(end 0.508 -0.4064)
						)
						(arc
							(start 0.508 0.4064)
							(mid 0.448484 0.550084)
							(end 0.3048 0.6096)
						)
						(arc
							(start -0.3048 0.6096)
							(mid -0.448484 0.550084)
							(end -0.508 0.4064)
						)
					)
					(width 0)
					(fill yes)
				)
			)
		)
	)
)
